(kicad_pcb
	(version 20241229)
	(generator "pcbnew")
	(generator_version "9.0")
	(general
		(thickness 1.6296)
		(legacy_teardrops no)
	)
	(paper "A3")
	(title_block
		(title "Thunderbolt to 10GbE adapter")
		(date "2026-04-21")
		(rev "1.1.0")
		(company "Antmicro Ltd")
		(comment 1 "www.antmicro.com")
		(comment 9 "footprints 37-41 of 703")
	)
	(layers
		(0 "F.Cu" signal)
		(4 "In1.Cu" signal)
		(6 "In2.Cu" signal)
		(8 "In3.Cu" signal)
		(10 "In4.Cu" signal)
		(12 "In5.Cu" signal)
		(14 "In6.Cu" signal)
		(2 "B.Cu" signal)
		(9 "F.Adhes" user "F.Adhesive")
		(11 "B.Adhes" user "B.Adhesive")
		(13 "F.Paste" user)
		(15 "B.Paste" user)
		(5 "F.SilkS" user "F.Silkscreen")
		(7 "B.SilkS" user "B.Silkscreen")
		(1 "F.Mask" user)
		(3 "B.Mask" user)
		(17 "Dwgs.User" user "User.Drawings")
		(19 "Cmts.User" user "User.Comments")
		(21 "Eco1.User" user "User.Eco1")
		(23 "Eco2.User" user "User.Eco2")
		(25 "Edge.Cuts" user)
		(27 "Margin" user)
		(31 "F.CrtYd" user "F.Courtyard")
		(29 "B.CrtYd" user "B.Courtyard")
		(35 "F.Fab" user)
		(33 "B.Fab" user)
	)
	(footprint "antmicro-footprints:C_0402_1005Metric"
		(layer "F.Cu")
		(at 120.4 128.6)
		(descr "Capacitor SMD 0402")
		(tags "capacitor SMD 0402")
		(property "Reference" "C43"
			(at -1 1.4 0)
			(layer "F.SilkS")
			(effects
				(font
					(size 0.7 0.7)
					(thickness 0.15)
				)
				(justify left bottom)
			)
		)
		(property "Value" "C_10p_0402"
			(at -1.022927 2.155213 0)
			(layer "F.Fab")
			(effects
				(font
					(size 0.7 0.7)
					(thickness 0.15)
				)
				(justify left bottom)
			)
		)
		(property "Datasheet" "https://www.murata.com/products/productdetail?partno=GCM1555C1H100GA16%23"
			(at 0 0 0)
			(layer "F.Fab")
			(hide yes)
			(effects
				(font
					(size 1.27 1.27)
					(thickness 0.15)
				)
			)
		)
		(property "Description" "SMD Multilayer Ceramic Capacitor, 10 pF, 50 V, 0402 [1005 Metric], ± 2%, C0G / NP0, GCM"
			(at 0 0 0)
			(layer "F.Fab")
			(hide yes)
			(effects
				(font
					(size 1.27 1.27)
					(thickness 0.15)
				)
			)
		)
		(property "MPN" "GCM1555C1H100GA16D"
			(at 0 0 0)
			(unlocked yes)
			(layer "F.Fab")
			(hide yes)
			(effects
				(font
					(size 1 1)
					(thickness 0.15)
				)
			)
		)
		(property "Manufacturer" "Murata"
			(at 0 0 0)
			(unlocked yes)
			(layer "F.Fab")
			(hide yes)
			(effects
				(font
					(size 1 1)
					(thickness 0.15)
				)
			)
		)
		(property "License" "Apache-2.0"
			(at 0 0 0)
			(unlocked yes)
			(layer "F.Fab")
			(hide yes)
			(effects
				(font
					(size 1 1)
					(thickness 0.15)
				)
			)
		)
		(property "Val" "10p"
			(at 0 0 0)
			(unlocked yes)
			(layer "F.Fab")
			(hide yes)
			(effects
				(font
					(size 1 1)
					(thickness 0.15)
				)
			)
		)
		(property "Voltage" "50V"
			(at 0 0 0)
			(unlocked yes)
			(layer "F.Fab")
			(hide yes)
			(effects
				(font
					(size 1 1)
					(thickness 0.15)
				)
			)
		)
		(property "Dielectric" "C0G"
			(at 0 0 0)
			(unlocked yes)
			(layer "F.Fab")
			(hide yes)
			(effects
				(font
					(size 1 1)
					(thickness 0.15)
				)
			)
		)
		(property "Author" "Antmicro"
			(at 0 0 0)
			(unlocked yes)
			(layer "F.Fab")
			(hide yes)
			(effects
				(font
					(size 1 1)
					(thickness 0.15)
				)
			)
		)
		(sheetname "/TB Controller/")
		(sheetfile "tb.kicad_sch")
		(attr smd)
		(fp_rect
			(start -0.925 -0.47)
			(end 0.925 0.47)
			(stroke
				(width 0.05)
				(type default)
			)
			(fill no)
			(layer "F.CrtYd")
		)
		(fp_line
			(start -0.494 -0.25)
			(end 0.504 -0.25)
			(stroke
				(width 0.15)
				(type solid)
			)
			(layer "F.Fab")
		)
		(fp_line
			(start -0.494 0.248)
			(end -0.494 -0.25)
			(stroke
				(width 0.15)
				(type solid)
			)
			(layer "F.Fab")
		)
		(fp_line
			(start 0.504 -0.25)
			(end 0.504 0.248)
			(stroke
				(width 0.15)
				(type solid)
			)
			(layer "F.Fab")
		)
		(fp_line
			(start 0.504 0.248)
			(end -0.494 0.248)
			(stroke
				(width 0.15)
				(type solid)
			)
			(layer "F.Fab")
		)
		(fp_text user "License: Apache-2.0"
			(at -0.939 5.799 0)
			(layer "F.Fab")
			(effects
				(font
					(size 0.7 0.7)
					(thickness 0.15)
				)
				(justify left bottom)
			)
		)
		(fp_text user "Author: Antmicro"
			(at -0.939 3.399 0)
			(layer "F.Fab")
			(effects
				(font
					(size 0.7 0.7)
					(thickness 0.15)
				)
				(justify left bottom)
			)
		)
		(fp_text user "${REFERENCE}"
			(at -0.939 4.599 0)
			(layer "F.Fab")
			(effects
				(font
					(size 0.7 0.7)
					(thickness 0.15)
				)
				(justify left bottom)
			)
		)
		(pad "1" smd roundrect
			(at -0.48 0)
			(size 0.59 0.64)
			(layers "F.Cu" "F.Mask" "F.Paste")
			(roundrect_rratio 0.25)
			(net 331 "/TB Controller/XTAL_25_OUT")
			(pintype "passive")
		)
		(pad "2" smd roundrect
			(at 0.48 0)
			(size 0.59 0.64)
			(layers "F.Cu" "F.Mask" "F.Paste")
			(roundrect_rratio 0.25)
			(net 23 "GND")
			(pintype "passive")
		)
	)
	(footprint "antmicro-footprints:C_0402_1005Metric"
		(layer "F.Cu")
		(at 156.500002 109.850002 90)
		(descr "Capacitor SMD 0402")
		(tags "capacitor SMD 0402")
		(property "Reference" "C126"
			(at -16.799996 13.650003 90)
			(layer "F.SilkS")
			(effects
				(font
					(size 0.7 0.7)
					(thickness 0.15)
				)
			)
		)
		(property "Value" "C_100n_0402"
			(at -1.022927 2.155213 90)
			(layer "F.Fab")
			(effects
				(font
					(size 0.7 0.7)
					(thickness 0.15)
				)
				(justify left bottom)
			)
		)
		(property "Datasheet" "https://www.murata.com/products/productdetail?partno=GRM155R61H104KE14%23"
			(at 0 0 90)
			(layer "F.Fab")
			(hide yes)
			(effects
				(font
					(size 1.27 1.27)
					(thickness 0.15)
				)
			)
		)
		(property "Description" "SMD Multilayer Ceramic Capacitor, 0.1 µF, 50 V, 0402 [1005 Metric], ± 10%, X5R, GRM Series"
			(at 0 0 90)
			(layer "F.Fab")
			(hide yes)
			(effects
				(font
					(size 1.27 1.27)
					(thickness 0.15)
				)
			)
		)
		(property "MPN" "GRM155R61H104KE14D"
			(at 0 0 90)
			(unlocked yes)
			(layer "F.Fab")
			(hide yes)
			(effects
				(font
					(size 1 1)
					(thickness 0.15)
				)
			)
		)
		(property "Manufacturer" "Murata"
			(at 0 0 90)
			(unlocked yes)
			(layer "F.Fab")
			(hide yes)
			(effects
				(font
					(size 1 1)
					(thickness 0.15)
				)
			)
		)
		(property "License" "Apache-2.0"
			(at 0 0 90)
			(unlocked yes)
			(layer "F.Fab")
			(hide yes)
			(effects
				(font
					(size 1 1)
					(thickness 0.15)
				)
			)
		)
		(property "Author" "Antmicro"
			(at 0 0 90)
			(unlocked yes)
			(layer "F.Fab")
			(hide yes)
			(effects
				(font
					(size 1 1)
					(thickness 0.15)
				)
			)
		)
		(property "Val" "100n"
			(at 0 0 90)
			(unlocked yes)
			(layer "F.Fab")
			(hide yes)
			(effects
				(font
					(size 1 1)
					(thickness 0.15)
				)
			)
		)
		(property "Voltage" "50V"
			(at 0 0 90)
			(unlocked yes)
			(layer "F.Fab")
			(hide yes)
			(effects
				(font
					(size 1 1)
					(thickness 0.15)
				)
			)
		)
		(property "Dielectric" "X5R"
			(at 0 0 90)
			(unlocked yes)
			(layer "F.Fab")
			(hide yes)
			(effects
				(font
					(size 1 1)
					(thickness 0.15)
				)
			)
		)
		(sheetname "/X710 DCDC converters/")
		(sheetfile "DCDC_converters_X710.kicad_sch")
		(attr smd)
		(fp_rect
			(start -0.925 -0.47)
			(end 0.925 0.47)
			(stroke
				(width 0.05)
				(type default)
			)
			(fill no)
			(layer "F.CrtYd")
		)
		(fp_line
			(start 0.504 -0.25)
			(end 0.504 0.248)
			(stroke
				(width 0.15)
				(type solid)
			)
			(layer "F.Fab")
		)
		(fp_line
			(start -0.494 -0.25)
			(end 0.504 -0.25)
			(stroke
				(width 0.15)
				(type solid)
			)
			(layer "F.Fab")
		)
		(fp_line
			(start 0.504 0.248)
			(end -0.494 0.248)
			(stroke
				(width 0.15)
				(type solid)
			)
			(layer "F.Fab")
		)
		(fp_line
			(start -0.494 0.248)
			(end -0.494 -0.25)
			(stroke
				(width 0.15)
				(type solid)
			)
			(layer "F.Fab")
		)
		(fp_text user "License: Apache-2.0"
			(at -0.939 5.799 90)
			(layer "F.Fab")
			(effects
				(font
					(size 0.7 0.7)
					(thickness 0.15)
				)
				(justify left bottom)
			)
		)
		(fp_text user "Author: Antmicro"
			(at -0.939 3.399 90)
			(layer "F.Fab")
			(effects
				(font
					(size 0.7 0.7)
					(thickness 0.15)
				)
				(justify left bottom)
			)
		)
		(fp_text user "${REFERENCE}"
			(at -0.939 4.599 90)
			(layer "F.Fab")
			(effects
				(font
					(size 0.7 0.7)
					(thickness 0.15)
				)
				(justify left bottom)
			)
		)
		(pad "1" smd roundrect
			(at -0.48 0 90)
			(size 0.59 0.64)
			(layers "F.Cu" "F.Mask" "F.Paste")
			(roundrect_rratio 0.25)
			(net 302 "/X710 DCDC converters/1V88_BST")
			(pintype "passive")
		)
		(pad "2" smd roundrect
			(at 0.48 0 90)
			(size 0.59 0.64)
			(layers "F.Cu" "F.Mask" "F.Paste")
			(roundrect_rratio 0.25)
			(net 241 "/X710 DCDC converters/1V88_SW")
			(pintype "passive")
		)
	)
	(footprint "antmicro-footprints:C_0603_1608Metric"
		(layer "F.Cu")
		(at 151.655 66.024999 90)
		(descr "Capacitor SMD 0603")
		(tags "capacitor 0603")
		(property "Reference" "C210"
			(at 12.424999 20.045 90)
			(layer "F.SilkS")
			(effects
				(font
					(size 0.7 0.7)
					(thickness 0.15)
				)
			)
		)
		(property "Value" "C_10u_10V_X7R_0603"
			(at -1.42757 1.770288 90)
			(layer "F.Fab")
			(effects
				(font
					(size 0.7 0.7)
					(thickness 0.15)
				)
				(justify left bottom)
			)
		)
		(property "Datasheet" "https://www.murata.com/products/productdetail?partno=GRM188Z71A106KA73%23"
			(at 0 0 90)
			(layer "F.Fab")
			(hide yes)
			(effects
				(font
					(size 1.27 1.27)
					(thickness 0.15)
				)
			)
		)
		(property "Description" "SMD Multilayer Ceramic Capacitor,  10µF, 10V, 0603, ±10%, X7R"
			(at 0 0 90)
			(layer "F.Fab")
			(hide yes)
			(effects
				(font
					(size 1.27 1.27)
					(thickness 0.15)
				)
			)
		)
		(property "MPN" "GRM188Z71A106KA73D"
			(at 0 0 90)
			(unlocked yes)
			(layer "F.Fab")
			(hide yes)
			(effects
				(font
					(size 1 1)
					(thickness 0.15)
				)
			)
		)
		(property "Val" "10u"
			(at 0 0 90)
			(unlocked yes)
			(layer "F.Fab")
			(hide yes)
			(effects
				(font
					(size 1 1)
					(thickness 0.15)
				)
			)
		)
		(property "Voltage" "10V"
			(at 0 0 90)
			(unlocked yes)
			(layer "F.Fab")
			(hide yes)
			(effects
				(font
					(size 1 1)
					(thickness 0.15)
				)
			)
		)
		(property "Dielectric" "X7R"
			(at 0 0 90)
			(unlocked yes)
			(layer "F.Fab")
			(hide yes)
			(effects
				(font
					(size 1 1)
					(thickness 0.15)
				)
			)
		)
		(property "Manufacturer" "Murata"
			(at 0 0 90)
			(unlocked yes)
			(layer "F.Fab")
			(hide yes)
			(effects
				(font
					(size 1 1)
					(thickness 0.15)
				)
			)
		)
		(property "License" "Apache-2.0"
			(at 0 0 90)
			(unlocked yes)
			(layer "F.Fab")
			(hide yes)
			(effects
				(font
					(size 1 1)
					(thickness 0.15)
				)
			)
		)
		(property "Author" "Antmicro"
			(at 0 0 90)
			(unlocked yes)
			(layer "F.Fab")
			(hide yes)
			(effects
				(font
					(size 1 1)
					(thickness 0.15)
				)
			)
		)
		(sheetname "/X710-AT2 power/")
		(sheetfile "x710-at2-power.kicad_sch")
		(attr smd)
		(fp_line
			(start -0.15 -0.4)
			(end 0.15 -0.4)
			(stroke
				(width 0.15)
				(type solid)
			)
			(layer "F.SilkS")
		)
		(fp_line
			(start -0.15 0.4)
			(end 0.15 0.4)
			(stroke
				(width 0.15)
				(type solid)
			)
			(layer "F.SilkS")
		)
		(fp_rect
			(start -1.25 -0.65)
			(end 1.25 0.65)
			(stroke
				(width 0.05)
				(type solid)
			)
			(fill no)
			(layer "F.CrtYd")
		)
		(fp_rect
			(start -0.8 -0.4)
			(end 0.8 0.4)
			(stroke
				(width 0.15)
				(type solid)
			)
			(fill no)
			(layer "F.Fab")
		)
		(fp_text user "${REFERENCE}"
			(at -1.682 3.895 90)
			(layer "F.Fab")
			(effects
				(font
					(size 0.7 0.7)
					(thickness 0.15)
				)
				(justify left bottom)
			)
		)
		(fp_text user "Author: Antmicro"
			(at -1.682 4.894 90)
			(layer "F.Fab")
			(effects
				(font
					(size 0.7 0.7)
					(thickness 0.15)
				)
				(justify left bottom)
			)
		)
		(fp_text user "License: Apache-2.0"
			(at -1.682 5.895 90)
			(layer "F.Fab")
			(effects
				(font
					(size 0.7 0.7)
					(thickness 0.15)
				)
				(justify left bottom)
			)
		)
		(pad "1" smd roundrect
			(at -0.7 0 90)
			(size 0.8 1)
			(layers "F.Cu" "F.Mask" "F.Paste")
			(roundrect_rratio 0.2)
			(net 23 "GND")
			(pintype "passive")
		)
		(pad "2" smd roundrect
			(at 0.7 0 90)
			(size 0.8 1)
			(layers "F.Cu" "F.Mask" "F.Paste")
			(roundrect_rratio 0.2)
			(net 1 "VCCA")
			(pintype "passive")
		)
	)
	(footprint "antmicro-footprints:C_0603_1608Metric_EIA"
		(layer "F.Cu")
		(at 139.500001 114.349999)
		(descr "Capacitor SMD 0603, IPC-7351 Density Level A")
		(tags "Capacitor 0603")
		(property "Reference" "C105"
			(at 16 16.600001 0)
			(layer "F.SilkS")
			(effects
				(font
					(size 0.7 0.7)
					(thickness 0.15)
				)
			)
		)
		(property "Value" "C_22u_16V_0603"
			(at -1.42757 1.770288 0)
			(layer "F.Fab")
			(effects
				(font
					(size 0.7 0.7)
					(thickness 0.15)
				)
				(justify left bottom)
			)
		)
		(property "Datasheet" "https://product.samsungsem.com/mlcc/CL10A226MO7JZN.do"
			(at 0 0 0)
			(layer "F.Fab")
			(hide yes)
			(effects
				(font
					(size 1.27 1.27)
					(thickness 0.15)
				)
			)
		)
		(property "Description" "SMD Multilayer Ceramic Capacitor"
			(at 0 0 0)
			(layer "F.Fab")
			(hide yes)
			(effects
				(font
					(size 1.27 1.27)
					(thickness 0.15)
				)
			)
		)
		(property "MPN" "CL10A226MO7JZNC"
			(at 0 0 0)
			(unlocked yes)
			(layer "F.Fab")
			(hide yes)
			(effects
				(font
					(size 1 1)
					(thickness 0.15)
				)
			)
		)
		(property "Manufacturer" "Samsung Electro-Mechanics"
			(at 0 0 0)
			(unlocked yes)
			(layer "F.Fab")
			(hide yes)
			(effects
				(font
					(size 1 1)
					(thickness 0.15)
				)
			)
		)
		(property "License" "Apache-2.0"
			(at 0 0 0)
			(unlocked yes)
			(layer "F.Fab")
			(hide yes)
			(effects
				(font
					(size 1 1)
					(thickness 0.15)
				)
			)
		)
		(property "Author" "Antmicro"
			(at 0 0 0)
			(unlocked yes)
			(layer "F.Fab")
			(hide yes)
			(effects
				(font
					(size 1 1)
					(thickness 0.15)
				)
			)
		)
		(property "Val" "22u"
			(at 0 0 0)
			(unlocked yes)
			(layer "F.Fab")
			(hide yes)
			(effects
				(font
					(size 1 1)
					(thickness 0.15)
				)
			)
		)
		(property "Voltage" "16V"
			(at 0 0 0)
			(unlocked yes)
			(layer "F.Fab")
			(hide yes)
			(effects
				(font
					(size 1 1)
					(thickness 0.15)
				)
			)
		)
		(property "Dielectric" ""
			(at 0 0 0)
			(unlocked yes)
			(layer "F.Fab")
			(hide yes)
			(effects
				(font
					(size 1 1)
					(thickness 0.15)
				)
			)
		)
		(sheetname "/X710 DCDC converters/")
		(sheetfile "DCDC_converters_X710.kicad_sch")
		(attr smd)
		(fp_line
			(start -0.15 -0.55)
			(end 0.15 -0.55)
			(stroke
				(width 0.15)
				(type solid)
			)
			(layer "F.SilkS")
		)
		(fp_line
			(start -0.15 0.55)
			(end 0.15 0.55)
			(stroke
				(width 0.15)
				(type solid)
			)
			(layer "F.SilkS")
		)
		(fp_rect
			(start -1.25 -0.65)
			(end 1.25 0.65)
			(stroke
				(width 0.05)
				(type solid)
			)
			(fill no)
			(layer "F.CrtYd")
		)
		(fp_rect
			(start -0.8 -0.45)
			(end 0.8 0.45)
			(stroke
				(width 0.15)
				(type solid)
			)
			(fill no)
			(layer "F.Fab")
		)
		(fp_text user "${REFERENCE}"
			(at -1.682 3.895 0)
			(layer "F.Fab")
			(effects
				(font
					(size 0.7 0.7)
					(thickness 0.15)
				)
				(justify left bottom)
			)
		)
		(fp_text user "Author: Antmicro"
			(at -1.682 4.894 0)
			(layer "F.Fab")
			(effects
				(font
					(size 0.7 0.7)
					(thickness 0.15)
				)
				(justify left bottom)
			)
		)
		(fp_text user "License: Apache-2.0"
			(at -1.682 5.895 0)
			(layer "F.Fab")
			(effects
				(font
					(size 0.7 0.7)
					(thickness 0.15)
				)
				(justify left bottom)
			)
		)
		(pad "1" smd roundrect
			(at -0.7 0)
			(size 0.8 1.1)
			(layers "F.Cu" "F.Mask" "F.Paste")
			(roundrect_rratio 0.2)
			(net 23 "GND")
			(pintype "passive")
		)
		(pad "2" smd roundrect
			(at 0.7 0)
			(size 0.8 1.1)
			(layers "F.Cu" "F.Mask" "F.Paste")
			(roundrect_rratio 0.2)
			(net 40 "+5V")
			(pintype "passive")
		)
	)
	(footprint "antmicro-footprints:C_0603_1608Metric_EIA"
		(layer "F.Cu")
		(at 131.955001 89.274999 -90)
		(descr "Capacitor SMD 0603, IPC-7351 Density Level A")
		(tags "Capacitor 0603")
		(property "Reference" "C262"
			(at 4.225001 15.705001 270)
			(layer "F.SilkS")
			(effects
				(font
					(size 0.7 0.7)
					(thickness 0.15)
				)
				(justify left bottom)
			)
		)
		(property "Value" "C_22u_16V_0603"
			(at -1.42757 1.770288 270)
			(layer "F.Fab")
			(effects
				(font
					(size 0.7 0.7)
					(thickness 0.15)
				)
				(justify left bottom)
			)
		)
		(property "Datasheet" "https://product.samsungsem.com/mlcc/CL10A226MO7JZN.do"
			(at 0 0 270)
			(layer "F.Fab")
			(hide yes)
			(effects
				(font
					(size 1.27 1.27)
					(thickness 0.15)
				)
			)
		)
		(property "Description" "SMD Multilayer Ceramic Capacitor"
			(at 0 0 270)
			(layer "F.Fab")
			(hide yes)
			(effects
				(font
					(size 1.27 1.27)
					(thickness 0.15)
				)
			)
		)
		(property "MPN" "CL10A226MO7JZNC"
			(at 0 0 270)
			(unlocked yes)
			(layer "F.Fab")
			(hide yes)
			(effects
				(font
					(size 1 1)
					(thickness 0.15)
				)
			)
		)
		(property "Manufacturer" "Samsung Electro-Mechanics"
			(at 0 0 270)
			(unlocked yes)
			(layer "F.Fab")
			(hide yes)
			(effects
				(font
					(size 1 1)
					(thickness 0.15)
				)
			)
		)
		(property "License" "Apache-2.0"
			(at 0 0 270)
			(unlocked yes)
			(layer "F.Fab")
			(hide yes)
			(effects
				(font
					(size 1 1)
					(thickness 0.15)
				)
			)
		)
		(property "Author" "Antmicro"
			(at 0 0 270)
			(unlocked yes)
			(layer "F.Fab")
			(hide yes)
			(effects
				(font
					(size 1 1)
					(thickness 0.15)
				)
			)
		)
		(property "Val" "22u"
			(at 0 0 270)
			(unlocked yes)
			(layer "F.Fab")
			(hide yes)
			(effects
				(font
					(size 1 1)
					(thickness 0.15)
				)
			)
		)
		(property "Voltage" "16V"
			(at 0 0 270)
			(unlocked yes)
			(layer "F.Fab")
			(hide yes)
			(effects
				(font
					(size 1 1)
					(thickness 0.15)
				)
			)
		)
		(property "Dielectric" ""
			(at 0 0 270)
			(unlocked yes)
			(layer "F.Fab")
			(hide yes)
			(effects
				(font
					(size 1 1)
					(thickness 0.15)
				)
			)
		)
		(sheetname "/X710-AT2 power/")
		(sheetfile "x710-at2-power.kicad_sch")
		(attr smd)
		(fp_line
			(start -0.15 0.55)
			(end 0.15 0.55)
			(stroke
				(width 0.15)
				(type solid)
			)
			(layer "F.SilkS")
		)
		(fp_line
			(start -0.15 -0.55)
			(end 0.15 -0.55)
			(stroke
				(width 0.15)
				(type solid)
			)
			(layer "F.SilkS")
		)
		(fp_rect
			(start -1.25 -0.65)
			(end 1.25 0.65)
			(stroke
				(width 0.05)
				(type solid)
			)
			(fill no)
			(layer "F.CrtYd")
		)
		(fp_rect
			(start -0.8 -0.45)
			(end 0.8 0.45)
			(stroke
				(width 0.15)
				(type solid)
			)
			(fill no)
			(layer "F.Fab")
		)
		(fp_text user "Author: Antmicro"
			(at -1.682 4.894 270)
			(layer "F.Fab")
			(effects
				(font
					(size 0.7 0.7)
					(thickness 0.15)
				)
				(justify left bottom)
			)
		)
		(fp_text user "License: Apache-2.0"
			(at -1.682 5.895 270)
			(layer "F.Fab")
			(effects
				(font
					(size 0.7 0.7)
					(thickness 0.15)
				)
				(justify left bottom)
			)
		)
		(fp_text user "${REFERENCE}"
			(at -1.682 3.895 270)
			(layer "F.Fab")
			(effects
				(font
					(size 0.7 0.7)
					(thickness 0.15)
				)
				(justify left bottom)
			)
		)
		(pad "1" smd roundrect
			(at -0.7 0 270)
			(size 0.8 1.1)
			(layers "F.Cu" "F.Mask" "F.Paste")
			(roundrect_rratio 0.2)
			(net 23 "GND")
			(pintype "passive")
		)
		(pad "2" smd roundrect
			(at 0.7 0 270)
			(size 0.8 1.1)
			(layers "F.Cu" "F.Mask" "F.Paste")
			(roundrect_rratio 0.2)
			(net 7 "+3V3")
			(pintype "passive")
		)
	)
)
